(kicad_pcb
	(version 20260206)
	(generator "pcbnew")
	(generator_version "10.0")
	(general
		(thickness 1.6)
		(legacy_teardrops no)
	)
	(paper "A4")
	(title_block
		(title "timecard-production-celestica-r4006 — R4006-B0001-02_R01.brd")
		(comment 1 "Time Appliance Project (Time Card) / footprints 950-955 of 1113")
	)
	(layers
		(0 "F.Cu" signal "TOP")
		(4 "In1.Cu" signal "L02_GND1")
		(6 "In2.Cu" signal "L03_SIG1")
		(8 "In3.Cu" signal "L04_GND2")
		(10 "In4.Cu" signal "L05_VCC1")
		(12 "In5.Cu" signal "L06_VCC2")
		(14 "In6.Cu" signal "L07_GND3")
		(16 "In7.Cu" signal "L08_SIG2")
		(18 "In8.Cu" signal "L09_GND4")
		(2 "B.Cu" signal "BOTTOM")
		(9 "F.Adhes" user "F.Adhesive")
		(11 "B.Adhes" user "B.Adhesive")
		(13 "F.Paste" user "Package Geometry/Pastemask Top")
		(15 "B.Paste" user "Package Geometry/Pastemask Bottom")
		(5 "F.SilkS" user "Ref Des/Silkscreen Top")
		(7 "B.SilkS" user "Ref Des/Silkscreen Bottom")
		(1 "F.Mask" user "Board Geometry/Soldermask Top")
		(3 "B.Mask" user "Board Geometry/Soldermask Bottom")
		(17 "Dwgs.User" user "User.Drawings")
		(19 "Cmts.User" user "User.Comments")
		(21 "Eco1.User" user "User.Eco1")
		(23 "Eco2.User" user "User.Eco2")
		(25 "Edge.Cuts" user "Board Geometry/Outline")
		(27 "Margin" user)
		(31 "F.CrtYd" user "Package Geometry/Place Bound Top")
		(29 "B.CrtYd" user "Package Geometry/Place Bound Bottom")
		(35 "F.Fab" user "Ref Des/Assembly Top")
		(33 "B.Fab" user "Ref Des/Assembly Bottom")
	)
	(footprint ""
		(layer "B.Cu")
		(at 16.764 -77.089 90)
		(property "Reference" "R332"
			(at -1.143 3.13563 270)
			(unlocked yes)
			(layer "B.SilkS")
			(effects
				(font
					(size 0.7874 0.5842)
					(thickness 0.1524)
				)
				(justify mirror)
			)
		)
		(property "Value" "VAL*"
			(at -0.02032 2.13233 90)
			(unlocked yes)
			(layer "B.Fab")
			(hide yes)
			(effects
				(font
					(size 0.7874 0.5842)
					(thickness 0.1524)
				)
				(justify mirror)
			)
		)
		(property "Tolerance" "TOL*"
			(at -0.044704 3.05435 90)
			(unlocked yes)
			(layer "Cmts.User")
			(hide yes)
			(effects
				(font
					(size 0.7874 0.5842)
					(thickness 0.1524)
				)
				(justify mirror)
			)
		)
		(property "User Part Number" "PARTNUM*"
			(at -0.02032 4.024884 90)
			(unlocked yes)
			(layer "Cmts.User")
			(hide yes)
			(effects
				(font
					(size 0.7874 0.5842)
					(thickness 0.1524)
				)
				(justify mirror)
			)
		)
		(property "Device Type" "RESISTOR-G155-133R0-01,33OHM,1%"
			(at -0.008382 1.210564 90)
			(unlocked yes)
			(layer "B.Fab")
			(hide yes)
			(effects
				(font
					(size 0.7874 0.5842)
					(thickness 0.1524)
				)
				(justify mirror)
			)
		)
		(duplicate_pad_numbers_are_jumpers no)
		(fp_line
			(start 1.143 -0.5588)
			(end 1.143 0.5588)
			(stroke
				(width 0.1)
				(type default)
			)
			(layer "B.SilkS")
		)
		(fp_line
			(start -1.143 -0.5588)
			(end 1.143 -0.5588)
			(stroke
				(width 0.1)
				(type default)
			)
			(layer "B.SilkS")
		)
		(fp_line
			(start 1.143 0.5588)
			(end -1.143 0.5588)
			(stroke
				(width 0.1)
				(type default)
			)
			(layer "B.SilkS")
		)
		(fp_line
			(start -1.143 0.5588)
			(end -1.143 -0.5588)
			(stroke
				(width 0.1)
				(type default)
			)
			(layer "B.SilkS")
		)
		(fp_rect
			(start 1.143 -0.5588)
			(end -1.143 0.5588)
			(stroke
				(width 0)
				(type default)
			)
			(fill no)
			(layer "B.CrtYd")
		)
		(fp_line
			(start 0.508 -0.3048)
			(end 0.508 0.3048)
			(stroke
				(width 0.1)
				(type default)
			)
			(layer "B.Fab")
		)
		(fp_line
			(start -0.508 -0.3048)
			(end 0.508 -0.3048)
			(stroke
				(width 0.1)
				(type default)
			)
			(layer "B.Fab")
		)
		(fp_line
			(start 0.508 0.3048)
			(end -0.508 0.3048)
			(stroke
				(width 0.1)
				(type default)
			)
			(layer "B.Fab")
		)
		(fp_line
			(start -0.508 0.3048)
			(end -0.508 -0.3048)
			(stroke
				(width 0.1)
				(type default)
			)
			(layer "B.Fab")
		)
		(pad "1" smd rect
			(at 0.5334 0 270)
			(size 0.7112 0.6096)
			(layers "B.Cu" "B.Mask" "B.Paste")
			(net "LM75B_I2C_SDA")
		)
		(pad "2" smd rect
			(at -0.5334 0 270)
			(size 0.7112 0.6096)
			(layers "B.Cu" "B.Mask" "B.Paste")
			(net "R_LM75B_1_I2C_SDA")
		)
		(zone
			(layer "B.Cu")
			(hatch none 0.5)
			(connect_pads
				(clearance 0)
			)
			(min_thickness 0.25)
			(keepout
				(tracks allowed)
				(vias not_allowed)
				(pads allowed)
				(copperpour not_allowed)
				(footprints allowed)
			)
			(placement
				(enabled no)
				(sheetname "")
			)
			(fill
				(thermal_gap 0.5)
				(thermal_bridge_width 0.5)
				(island_removal_mode 0)
			)
			(polygon
				(pts
					(xy 16.4592 -77.1652) (xy 16.4592 -77.0128) (xy 17.0688 -77.0128) (xy 17.0688 -77.1652)
				)
			)
		)
	)
	(footprint ""
		(layer "B.Cu")
		(at 112.84712 -40.323262 -90)
		(property "Reference" "C161"
			(at 1.397762 42.01795 270)
			(unlocked yes)
			(layer "B.SilkS")
			(effects
				(font
					(size 0.635 0.4064)
					(thickness 0.1524)
				)
				(justify mirror)
			)
		)
		(property "Value" "VAL*"
			(at 0 3.718306 270)
			(unlocked yes)
			(layer "B.Fab")
			(hide yes)
			(effects
				(font
					(size 0.7874 0.5842)
					(thickness 0.127)
				)
				(justify mirror)
			)
		)
		(property "Device Type" "CAPACITOR-G105-0B104-CK,0.1UF,A"
			(at 0 1.432306 270)
			(unlocked yes)
			(layer "B.Fab")
			(hide yes)
			(effects
				(font
					(size 0.7874 0.5842)
					(thickness 0.127)
				)
				(justify mirror)
			)
		)
		(property "User Part Number" "PARTNUM*"
			(at 0 2.575306 270)
			(unlocked yes)
			(layer "Cmts.User")
			(hide yes)
			(effects
				(font
					(size 0.7874 0.5842)
					(thickness 0.127)
				)
				(justify mirror)
			)
		)
		(property "Tolerance" "TOL*"
			(at 0 4.861306 270)
			(unlocked yes)
			(layer "Cmts.User")
			(hide yes)
			(effects
				(font
					(size 0.7874 0.5842)
					(thickness 0.127)
				)
				(justify mirror)
			)
		)
		(duplicate_pad_numbers_are_jumpers no)
		(fp_line
			(start -0.970026 0.4699)
			(end 0.970026 0.4699)
			(stroke
				(width 0.1)
				(type default)
			)
			(layer "B.SilkS")
		)
		(fp_line
			(start 0.970026 0.4699)
			(end 0.970026 -0.4699)
			(stroke
				(width 0.1)
				(type default)
			)
			(layer "B.SilkS")
		)
		(fp_line
			(start -0.970026 -0.4699)
			(end -0.970026 0.4699)
			(stroke
				(width 0.1)
				(type default)
			)
			(layer "B.SilkS")
		)
		(fp_line
			(start 0.970026 -0.4699)
			(end -0.970026 -0.4699)
			(stroke
				(width 0.1)
				(type default)
			)
			(layer "B.SilkS")
		)
		(fp_poly
			(pts
				(xy 0.970026 0.4699) (xy -0.970026 0.4699) (xy -0.970026 -0.4699) (xy 0.970026 -0.4699)
			)
			(stroke
				(width 0)
				(type default)
			)
			(fill no)
			(layer "B.CrtYd")
		)
		(fp_line
			(start -0.508 0.3048)
			(end 0.508 0.3048)
			(stroke
				(width 0.1)
				(type default)
			)
			(layer "B.Fab")
		)
		(fp_line
			(start 0.508 0.3048)
			(end 0.508 -0.3048)
			(stroke
				(width 0.1)
				(type default)
			)
			(layer "B.Fab")
		)
		(fp_line
			(start -0.508 -0.3048)
			(end -0.508 0.3048)
			(stroke
				(width 0.1)
				(type default)
			)
			(layer "B.Fab")
		)
		(fp_line
			(start 0.508 -0.3048)
			(end -0.508 -0.3048)
			(stroke
				(width 0.1)
				(type default)
			)
			(layer "B.Fab")
		)
		(pad "1" smd circle
			(at 0.500126 0 90)
			(size 0.635 0.635)
			(layers "B.Cu" "B.Mask" "B.Paste")
			(net "XP1R0V_FPGA_VCCINT")
		)
		(pad "2" smd circle
			(at -0.500126 0 90)
			(size 0.635 0.635)
			(layers "B.Cu" "B.Mask" "B.Paste")
			(net "SG")
		)
	)
	(footprint ""
		(layer "B.Cu")
		(at 96.5454 -64.2874 90)
		(property "Reference" "R286"
			(at 3.4036 0.31623 270)
			(unlocked yes)
			(layer "B.SilkS")
			(effects
				(font
					(size 0.7874 0.5842)
					(thickness 0.1524)
				)
				(justify mirror)
			)
		)
		(property "Value" "VAL*"
			(at -0.02032 2.13233 90)
			(unlocked yes)
			(layer "B.Fab")
			(hide yes)
			(effects
				(font
					(size 0.7874 0.5842)
					(thickness 0.1524)
				)
				(justify mirror)
			)
		)
		(property "Tolerance" "TOL*"
			(at -0.044704 3.05435 90)
			(unlocked yes)
			(layer "Cmts.User")
			(hide yes)
			(effects
				(font
					(size 0.7874 0.5842)
					(thickness 0.1524)
				)
				(justify mirror)
			)
		)
		(property "User Part Number" "PARTNUM*"
			(at -0.02032 4.024884 90)
			(unlocked yes)
			(layer "Cmts.User")
			(hide yes)
			(effects
				(font
					(size 0.7874 0.5842)
					(thickness 0.1524)
				)
				(justify mirror)
			)
		)
		(property "Device Type" "RESISTOR-G155-14701-01,4.7KOHMA"
			(at -0.008382 1.210564 90)
			(unlocked yes)
			(layer "B.Fab")
			(hide yes)
			(effects
				(font
					(size 0.7874 0.5842)
					(thickness 0.1524)
				)
				(justify mirror)
			)
		)
		(duplicate_pad_numbers_are_jumpers no)
		(fp_line
			(start 1.143 -0.5588)
			(end 1.143 0.5588)
			(stroke
				(width 0.1)
				(type default)
			)
			(layer "B.SilkS")
		)
		(fp_line
			(start -1.143 -0.5588)
			(end 1.143 -0.5588)
			(stroke
				(width 0.1)
				(type default)
			)
			(layer "B.SilkS")
		)
		(fp_line
			(start 1.143 0.5588)
			(end -1.143 0.5588)
			(stroke
				(width 0.1)
				(type default)
			)
			(layer "B.SilkS")
		)
		(fp_line
			(start -1.143 0.5588)
			(end -1.143 -0.5588)
			(stroke
				(width 0.1)
				(type default)
			)
			(layer "B.SilkS")
		)
		(fp_poly
			(pts
				(xy 1.143 0.5588) (xy -1.143 0.5588) (xy -1.143 -0.5588) (xy 1.143 -0.5588)
			)
			(stroke
				(width 0)
				(type default)
			)
			(fill no)
			(layer "B.CrtYd")
		)
		(fp_line
			(start 0.508 -0.3048)
			(end 0.508 0.3048)
			(stroke
				(width 0.1)
				(type default)
			)
			(layer "B.Fab")
		)
		(fp_line
			(start -0.508 -0.3048)
			(end 0.508 -0.3048)
			(stroke
				(width 0.1)
				(type default)
			)
			(layer "B.Fab")
		)
		(fp_line
			(start 0.508 0.3048)
			(end -0.508 0.3048)
			(stroke
				(width 0.1)
				(type default)
			)
			(layer "B.Fab")
		)
		(fp_line
			(start -0.508 0.3048)
			(end -0.508 -0.3048)
			(stroke
				(width 0.1)
				(type default)
			)
			(layer "B.Fab")
		)
		(pad "1" smd rect
			(at 0.5334 0 270)
			(size 0.7112 0.6096)
			(layers "B.Cu" "B.Mask" "B.Paste")
			(net "SG")
		)
		(pad "2" smd rect
			(at -0.5334 0 270)
			(size 0.7112 0.6096)
			(layers "B.Cu" "B.Mask" "B.Paste")
			(net "FPGA_IO_3")
		)
		(zone
			(layer "B.Cu")
			(hatch none 0.5)
			(connect_pads
				(clearance 0)
			)
			(min_thickness 0.25)
			(keepout
				(tracks allowed)
				(vias not_allowed)
				(pads allowed)
				(copperpour not_allowed)
				(footprints allowed)
			)
			(placement
				(enabled no)
				(sheetname "")
			)
			(fill
				(thermal_gap 0.5)
				(thermal_bridge_width 0.5)
				(island_removal_mode 0)
			)
			(polygon
				(pts
					(xy 96.8502 -64.3636) (xy 96.2406 -64.3636) (xy 96.2406 -64.2112) (xy 96.8502 -64.2112)
				)
			)
		)
		(zone
			(layer "B.Cu")
			(hatch none 0.5)
			(connect_pads
				(clearance 0)
			)
			(min_thickness 0.25)
			(keepout
				(tracks not_allowed)
				(vias allowed)
				(pads allowed)
				(copperpour not_allowed)
				(footprints allowed)
			)
			(placement
				(enabled no)
				(sheetname "")
			)
			(fill
				(thermal_gap 0.5)
				(thermal_bridge_width 0.5)
				(island_removal_mode 0)
			)
			(polygon
				(pts
					(xy 96.8502 -64.3636) (xy 96.2406 -64.3636) (xy 96.2406 -64.2112) (xy 96.8502 -64.2112)
				)
			)
		)
	)
	(footprint ""
		(layer "B.Cu")
		(at 7.366 -72.39 90)
		(property "Reference" "R334"
			(at -0.381 2.75463 270)
			(unlocked yes)
			(layer "B.SilkS")
			(effects
				(font
					(size 0.7874 0.5842)
					(thickness 0.1524)
				)
				(justify mirror)
			)
		)
		(property "Value" "VAL*"
			(at -0.02032 2.13233 90)
			(unlocked yes)
			(layer "B.Fab")
			(hide yes)
			(effects
				(font
					(size 0.7874 0.5842)
					(thickness 0.1524)
				)
				(justify mirror)
			)
		)
		(property "Tolerance" "TOL*"
			(at -0.044704 3.05435 90)
			(unlocked yes)
			(layer "Cmts.User")
			(hide yes)
			(effects
				(font
					(size 0.7874 0.5842)
					(thickness 0.1524)
				)
				(justify mirror)
			)
		)
		(property "User Part Number" "PARTNUM*"
			(at -0.02032 4.024884 90)
			(unlocked yes)
			(layer "Cmts.User")
			(hide yes)
			(effects
				(font
					(size 0.7874 0.5842)
					(thickness 0.1524)
				)
				(justify mirror)
			)
		)
		(property "Device Type" "RESISTOR-G155-11001-01,1KOHM,1%"
			(at -0.008382 1.210564 90)
			(unlocked yes)
			(layer "B.Fab")
			(hide yes)
			(effects
				(font
					(size 0.7874 0.5842)
					(thickness 0.1524)
				)
				(justify mirror)
			)
		)
		(duplicate_pad_numbers_are_jumpers no)
		(fp_line
			(start 1.143 -0.5588)
			(end 1.143 0.5588)
			(stroke
				(width 0.1)
				(type default)
			)
			(layer "B.SilkS")
		)
		(fp_line
			(start -1.143 -0.5588)
			(end 1.143 -0.5588)
			(stroke
				(width 0.1)
				(type default)
			)
			(layer "B.SilkS")
		)
		(fp_line
			(start 1.143 0.5588)
			(end -1.143 0.5588)
			(stroke
				(width 0.1)
				(type default)
			)
			(layer "B.SilkS")
		)
		(fp_line
			(start -1.143 0.5588)
			(end -1.143 -0.5588)
			(stroke
				(width 0.1)
				(type default)
			)
			(layer "B.SilkS")
		)
		(fp_rect
			(start 1.143 0.5588)
			(end -1.143 -0.5588)
			(stroke
				(width 0)
				(type default)
			)
			(fill no)
			(layer "B.CrtYd")
		)
		(fp_line
			(start 0.508 -0.3048)
			(end 0.508 0.3048)
			(stroke
				(width 0.1)
				(type default)
			)
			(layer "B.Fab")
		)
		(fp_line
			(start -0.508 -0.3048)
			(end 0.508 -0.3048)
			(stroke
				(width 0.1)
				(type default)
			)
			(layer "B.Fab")
		)
		(fp_line
			(start 0.508 0.3048)
			(end -0.508 0.3048)
			(stroke
				(width 0.1)
				(type default)
			)
			(layer "B.Fab")
		)
		(fp_line
			(start -0.508 0.3048)
			(end -0.508 -0.3048)
			(stroke
				(width 0.1)
				(type default)
			)
			(layer "B.Fab")
		)
		(pad "1" smd rect
			(at 0.5334 0 270)
			(size 0.7112 0.6096)
			(layers "B.Cu" "B.Mask" "B.Paste")
			(net "UNNAMED_6_LM75BDPTSSOP8_I34_A2")
		)
		(pad "2" smd rect
			(at -0.5334 0 270)
			(size 0.7112 0.6096)
			(layers "B.Cu" "B.Mask" "B.Paste")
			(net "SG")
		)
		(zone
			(layer "B.Cu")
			(hatch none 0.5)
			(connect_pads
				(clearance 0)
			)
			(min_thickness 0.25)
			(keepout
				(tracks allowed)
				(vias not_allowed)
				(pads allowed)
				(copperpour not_allowed)
				(footprints allowed)
			)
			(placement
				(enabled no)
				(sheetname "")
			)
			(fill
				(thermal_gap 0.5)
				(thermal_bridge_width 0.5)
				(island_removal_mode 0)
			)
			(polygon
				(pts
					(xy 7.6708 -72.4662) (xy 7.0612 -72.4662) (xy 7.0612 -72.3138) (xy 7.6708 -72.3138)
				)
			)
		)
	)
	(footprint ""
		(layer "B.Cu")
		(at 127.889 -98.425 90)
		(property "Reference" "C78"
			(at -2.794 -0.42037 270)
			(unlocked yes)
			(layer "B.SilkS")
			(effects
				(font
					(size 0.7874 0.5842)
					(thickness 0.1524)
				)
				(justify mirror)
			)
		)
		(property "Value" "VAL*"
			(at -0.0762 2.067306 90)
			(unlocked yes)
			(layer "B.Fab")
			(hide yes)
			(effects
				(font
					(size 0.7874 0.5842)
					(thickness 0.1524)
				)
				(justify mirror)
			)
		)
		(property "Device Type" "CAPACITOR-G105-0B104-EK,0.1UF,A"
			(at -0.0508 1.127506 90)
			(unlocked yes)
			(layer "B.Fab")
			(hide yes)
			(effects
				(font
					(size 0.7874 0.5842)
					(thickness 0.1524)
				)
				(justify mirror)
			)
		)
		(property "User Part Number" "PARTNUM*"
			(at -0.1016 4.023106 90)
			(unlocked yes)
			(layer "Cmts.User")
			(hide yes)
			(effects
				(font
					(size 0.7874 0.5842)
					(thickness 0.1524)
				)
				(justify mirror)
			)
		)
		(property "Tolerance" "TOL*"
			(at -0.0762 3.032506 90)
			(unlocked yes)
			(layer "Cmts.User")
			(hide yes)
			(effects
				(font
					(size 0.7874 0.5842)
					(thickness 0.1524)
				)
				(justify mirror)
			)
		)
		(duplicate_pad_numbers_are_jumpers no)
		(fp_line
			(start 1.143 -0.5588)
			(end 1.143 0.5588)
			(stroke
				(width 0.1)
				(type default)
			)
			(layer "B.SilkS")
		)
		(fp_line
			(start -1.143 -0.5588)
			(end 1.143 -0.5588)
			(stroke
				(width 0.1)
				(type default)
			)
			(layer "B.SilkS")
		)
		(fp_line
			(start 1.143 0.5588)
			(end -1.143 0.5588)
			(stroke
				(width 0.1)
				(type default)
			)
			(layer "B.SilkS")
		)
		(fp_line
			(start -1.143 0.5588)
			(end -1.143 -0.5588)
			(stroke
				(width 0.1)
				(type default)
			)
			(layer "B.SilkS")
		)
		(fp_rect
			(start -1.143 -0.5588)
			(end 1.143 0.5588)
			(stroke
				(width 0)
				(type default)
			)
			(fill no)
			(layer "B.CrtYd")
		)
		(fp_line
			(start 0.508 -0.3048)
			(end 0.508 0.3048)
			(stroke
				(width 0.1)
				(type default)
			)
			(layer "B.Fab")
		)
		(fp_line
			(start -0.508 -0.3048)
			(end 0.508 -0.3048)
			(stroke
				(width 0.1)
				(type default)
			)
			(layer "B.Fab")
		)
		(fp_line
			(start 0.508 0.3048)
			(end -0.508 0.3048)
			(stroke
				(width 0.1)
				(type default)
			)
			(layer "B.Fab")
		)
		(fp_line
			(start -0.508 0.3048)
			(end -0.508 -0.3048)
			(stroke
				(width 0.1)
				(type default)
			)
			(layer "B.Fab")
		)
		(pad "1" smd rect
			(at 0.5334 0 270)
			(size 0.7112 0.6096)
			(layers "B.Cu" "B.Mask" "B.Paste")
			(net "XP5R0V_VCC_ANT")
		)
		(pad "2" smd rect
			(at -0.5334 0 270)
			(size 0.7112 0.6096)
			(layers "B.Cu" "B.Mask" "B.Paste")
			(net "SG")
		)
		(zone
			(layer "B.Cu")
			(hatch none 0.5)
			(connect_pads
				(clearance 0)
			)
			(min_thickness 0.25)
			(keepout
				(tracks allowed)
				(vias not_allowed)
				(pads allowed)
				(copperpour not_allowed)
				(footprints allowed)
			)
			(placement
				(enabled no)
				(sheetname "")
			)
			(fill
				(thermal_gap 0.5)
				(thermal_bridge_width 0.5)
				(island_removal_mode 0)
			)
			(polygon
				(pts
					(xy 127.5842 -98.3488) (xy 128.1938 -98.3488) (xy 128.1938 -98.5012) (xy 127.5842 -98.5012)
				)
			)
		)
	)
	(footprint ""
		(layer "B.Cu")
		(at 118.847108 -54.323234 -90)
		(property "Reference" "C154"
			(at -3.461766 0.014478 270)
			(unlocked yes)
			(layer "B.SilkS")
			(effects
				(font
					(size 0.7874 0.5842)
					(thickness 0.1524)
				)
				(justify mirror)
			)
		)
		(property "Value" "VAL*"
			(at 0 3.718306 270)
			(unlocked yes)
			(layer "B.Fab")
			(hide yes)
			(effects
				(font
					(size 0.7874 0.5842)
					(thickness 0.127)
				)
				(justify mirror)
			)
		)
		(property "Device Type" "CAPACITOR-G105-0F475-BM,4.7UF,A"
			(at 0 1.432306 270)
			(unlocked yes)
			(layer "B.Fab")
			(hide yes)
			(effects
				(font
					(size 0.7874 0.5842)
					(thickness 0.127)
				)
				(justify mirror)
			)
		)
		(property "User Part Number" "PARTNUM*"
			(at 0 2.575306 270)
			(unlocked yes)
			(layer "Cmts.User")
			(hide yes)
			(effects
				(font
					(size 0.7874 0.5842)
					(thickness 0.127)
				)
				(justify mirror)
			)
		)
		(property "Tolerance" "TOL*"
			(at 0 4.861306 270)
			(unlocked yes)
			(layer "Cmts.User")
			(hide yes)
			(effects
				(font
					(size 0.7874 0.5842)
					(thickness 0.127)
				)
				(justify mirror)
			)
		)
		(duplicate_pad_numbers_are_jumpers no)
		(fp_line
			(start -0.970026 0.4699)
			(end 0.970026 0.4699)
			(stroke
				(width 0.1)
				(type default)
			)
			(layer "B.SilkS")
		)
		(fp_line
			(start 0.970026 0.4699)
			(end 0.970026 -0.4699)
			(stroke
				(width 0.1)
				(type default)
			)
			(layer "B.SilkS")
		)
		(fp_line
			(start -0.970026 -0.4699)
			(end -0.970026 0.4699)
			(stroke
				(width 0.1)
				(type default)
			)
			(layer "B.SilkS")
		)
		(fp_line
			(start 0.970026 -0.4699)
			(end -0.970026 -0.4699)
			(stroke
				(width 0.1)
				(type default)
			)
			(layer "B.SilkS")
		)
		(fp_poly
			(pts
				(xy 0.970026 0.4699) (xy -0.970026 0.4699) (xy -0.970026 -0.4699) (xy 0.970026 -0.4699)
			)
			(stroke
				(width 0)
				(type default)
			)
			(fill no)
			(layer "B.CrtYd")
		)
		(fp_line
			(start -0.508 0.3048)
			(end 0.508 0.3048)
			(stroke
				(width 0.1)
				(type default)
			)
			(layer "B.Fab")
		)
		(fp_line
			(start 0.508 0.3048)
			(end 0.508 -0.3048)
			(stroke
				(width 0.1)
				(type default)
			)
			(layer "B.Fab")
		)
		(fp_line
			(start -0.508 -0.3048)
			(end -0.508 0.3048)
			(stroke
				(width 0.1)
				(type default)
			)
			(layer "B.Fab")
		)
		(fp_line
			(start 0.508 -0.3048)
			(end -0.508 -0.3048)
			(stroke
				(width 0.1)
				(type default)
			)
			(layer "B.Fab")
		)
		(pad "1" smd circle
			(at 0.500126 0 90)
			(size 0.635 0.635)
			(layers "B.Cu" "B.Mask" "B.Paste")
			(net "XP3R3V_FPGA")
		)
		(pad "2" smd circle
			(at -0.500126 0 90)
			(size 0.635 0.635)
			(layers "B.Cu" "B.Mask" "B.Paste")
			(net "SG")
		)
	)
)
